(kicad_pcb
	(version 20260206)
	(generator "pcbnew")
	(generator_version "10.0")
	(general
		(thickness 1.6)
		(legacy_teardrops no)
	)
	(paper "A4")
	(title_block
		(title "Wiwynn_Tioga_Pass_MB.brd")
		(comment 1 "Tioga Pass / footprints 4290-4296 of 4770")
	)
	(layers
		(0 "F.Cu" signal "TOP")
		(4 "In1.Cu" signal "L2GND")
		(6 "In2.Cu" signal "L3")
		(8 "In3.Cu" signal "L4GND")
		(10 "In4.Cu" signal "L5")
		(12 "In5.Cu" signal "L6GND")
		(14 "In6.Cu" signal "L7VCC")
		(16 "In7.Cu" signal "L8VCC")
		(18 "In8.Cu" signal "L9GND")
		(20 "In9.Cu" signal "L10")
		(22 "In10.Cu" signal "L11GND")
		(24 "In11.Cu" signal "L12")
		(26 "In12.Cu" signal "L13GND")
		(2 "B.Cu" signal "BOTTOM")
		(9 "F.Adhes" user "F.Adhesive")
		(11 "B.Adhes" user "B.Adhesive")
		(13 "F.Paste" user "Package Geometry/Pastemask Top")
		(15 "B.Paste" user "Package Geometry/Pastemask Bottom")
		(5 "F.SilkS" user "Ref Des/Silkscreen Top")
		(7 "B.SilkS" user "Ref Des/Silkscreen Bottom")
		(1 "F.Mask" user "Board Geometry/Soldermask Top")
		(3 "B.Mask" user "Board Geometry/Soldermask Bottom")
		(17 "Dwgs.User" user "User.Drawings")
		(19 "Cmts.User" user "User.Comments")
		(21 "Eco1.User" user "User.Eco1")
		(23 "Eco2.User" user "User.Eco2")
		(25 "Edge.Cuts" user "Board Geometry/Outline")
		(27 "Margin" user)
		(31 "F.CrtYd" user "Package Geometry/Place Bound Top")
		(29 "B.CrtYd" user "Package Geometry/Place Bound Bottom")
		(35 "F.Fab" user "Ref Des/Assembly Top")
		(33 "B.Fab" user "Ref Des/Assembly Bottom")
	)
	(footprint ""
		(layer "B.Cu")
		(at 384.7084 -137.541)
		(property "Reference" "C3L24"
			(at 0 0 0)
			(layer "B.SilkS")
			(hide yes)
			(effects
				(font
					(size 1.27 1.27)
				)
				(justify mirror)
			)
		)
		(property "Value" ""
			(at 0 0 0)
			(layer "B.Fab")
			(effects
				(font
					(size 1.27 1.27)
				)
				(justify mirror)
			)
		)
		(duplicate_pad_numbers_are_jumpers no)
		(fp_poly
			(pts
				(xy 0.4953 -0.2032) (xy -0.4953 -0.2032) (xy -0.4953 1.6002) (xy 0.4953 1.6002)
			)
			(stroke
				(width 0)
				(type default)
			)
			(fill no)
			(layer "B.CrtYd")
		)
		(fp_line
			(start -0.4953 -0.2032)
			(end -0.4953 1.6002)
			(stroke
				(width 0.1)
				(type default)
			)
			(layer "B.Fab")
		)
		(fp_line
			(start -0.4953 1.6002)
			(end 0.4953 1.6002)
			(stroke
				(width 0.1)
				(type default)
			)
			(layer "B.Fab")
		)
		(fp_line
			(start 0.4953 -0.2032)
			(end -0.4953 -0.2032)
			(stroke
				(width 0.1)
				(type default)
			)
			(layer "B.Fab")
		)
		(fp_line
			(start 0.4953 1.6002)
			(end 0.4953 -0.2032)
			(stroke
				(width 0.1)
				(type default)
			)
			(layer "B.Fab")
		)
		(pad "1" smd rect
			(at 0 0 180)
			(size 0.762 0.889)
			(layers "B.Cu" "B.Mask" "B.Paste")
			(net "PVNN_PCH_STBY")
		)
		(pad "2" smd rect
			(at 0 1.397 180)
			(size 0.762 0.889)
			(layers "B.Cu" "B.Mask" "B.Paste")
			(net "GND")
		)
		(zone
			(layer "B.Cu")
			(hatch none 0.5)
			(connect_pads
				(clearance 0)
			)
			(min_thickness 0.25)
			(keepout
				(tracks not_allowed)
				(vias allowed)
				(pads allowed)
				(copperpour not_allowed)
				(footprints allowed)
			)
			(placement
				(enabled no)
				(sheetname "")
			)
			(fill
				(thermal_gap 0.5)
				(thermal_bridge_width 0.5)
				(island_removal_mode 0)
			)
			(polygon
				(pts
					(xy 385.0894 -137.0965) (xy 384.3274 -137.0965) (xy 384.3274 -136.5885) (xy 385.0894 -136.5885)
				)
			)
		)
	)
	(footprint ""
		(layer "B.Cu")
		(at 266.397232 -145.0086 90)
		(property "Reference" "C5L9"
			(at -1.848866 0.752348 90)
			(unlocked yes)
			(layer "B.SilkS")
			(effects
				(font
					(size 1.27 0.9652)
					(thickness 0.1524)
				)
				(justify mirror)
			)
		)
		(property "Value" ""
			(at 0 0 90)
			(layer "B.Fab")
			(effects
				(font
					(size 1.27 1.27)
				)
				(justify mirror)
			)
		)
		(duplicate_pad_numbers_are_jumpers no)
		(fp_rect
			(start 0.500126 1.598422)
			(end -0.500126 -0.201422)
			(stroke
				(width 0)
				(type default)
			)
			(fill no)
			(layer "B.CrtYd")
		)
		(fp_line
			(start 0.500126 -0.201422)
			(end -0.500126 -0.201422)
			(stroke
				(width 0.1)
				(type default)
			)
			(layer "B.Fab")
		)
		(fp_line
			(start -0.500126 -0.201422)
			(end -0.500126 1.598422)
			(stroke
				(width 0.1)
				(type default)
			)
			(layer "B.Fab")
		)
		(fp_line
			(start 0.500126 1.598422)
			(end 0.500126 -0.201422)
			(stroke
				(width 0.1)
				(type default)
			)
			(layer "B.Fab")
		)
		(fp_line
			(start -0.500126 1.598422)
			(end 0.500126 1.598422)
			(stroke
				(width 0.1)
				(type default)
			)
			(layer "B.Fab")
		)
		(pad "1" smd rect
			(at 0 0)
			(size 0.889 0.9906)
			(layers "B.Cu" "B.Mask" "B.Paste")
			(net "PVDDQ_DEF")
		)
		(pad "2" smd rect
			(at 0 1.397)
			(size 0.889 0.9906)
			(layers "B.Cu" "B.Mask" "B.Paste")
			(net "GND")
		)
		(zone
			(layer "B.Cu")
			(hatch none 0.5)
			(connect_pads
				(clearance 0)
			)
			(min_thickness 0.25)
			(keepout
				(tracks not_allowed)
				(vias allowed)
				(pads allowed)
				(copperpour not_allowed)
				(footprints allowed)
			)
			(placement
				(enabled no)
				(sheetname "")
			)
			(fill
				(thermal_gap 0.5)
				(thermal_bridge_width 0.5)
				(island_removal_mode 0)
			)
			(polygon
				(pts
					(xy 267.349732 -145.5039) (xy 266.841732 -145.5039) (xy 266.841732 -144.5133) (xy 267.349732 -144.5133)
				)
			)
		)
		(zone
			(layer "B.Cu")
			(hatch none 0.5)
			(connect_pads
				(clearance 0)
			)
			(min_thickness 0.25)
			(keepout
				(tracks allowed)
				(vias not_allowed)
				(pads allowed)
				(copperpour not_allowed)
				(footprints allowed)
			)
			(placement
				(enabled no)
				(sheetname "")
			)
			(fill
				(thermal_gap 0.5)
				(thermal_bridge_width 0.5)
				(island_removal_mode 0)
			)
			(polygon
				(pts
					(xy 267.349732 -145.5039) (xy 266.841732 -145.5039) (xy 266.841732 -144.5133) (xy 267.349732 -144.5133)
				)
			)
		)
	)
	(footprint ""
		(layer "B.Cu")
		(at 195.2244 -55.88 90)
		(property "Reference" "CT2"
			(at 0.8382 -0.84963 90)
			(unlocked yes)
			(layer "B.SilkS")
			(effects
				(font
					(size 0.7874 0.5842)
					(thickness 0.1524)
				)
				(justify left mirror)
			)
		)
		(property "Value" ""
			(at 0 0 90)
			(layer "B.Fab")
			(effects
				(font
					(size 1.27 1.27)
				)
				(justify mirror)
			)
		)
		(duplicate_pad_numbers_are_jumpers no)
		(fp_poly
			(pts
				(xy -0.3048 -0.1016) (xy -0.3048 0.9906) (xy 0.3048 0.9906) (xy 0.3048 -0.1016)
			)
			(stroke
				(width 0)
				(type default)
			)
			(fill no)
			(layer "B.CrtYd")
		)
		(fp_line
			(start 0.3048 -0.1016)
			(end 0.3048 0.9906)
			(stroke
				(width 0.1)
				(type default)
			)
			(layer "B.Fab")
		)
		(fp_line
			(start -0.3048 -0.1016)
			(end 0.3048 -0.1016)
			(stroke
				(width 0.1)
				(type default)
			)
			(layer "B.Fab")
		)
		(fp_line
			(start 0.3048 0.9906)
			(end -0.3048 0.9906)
			(stroke
				(width 0.1)
				(type default)
			)
			(layer "B.Fab")
		)
		(fp_line
			(start -0.3048 0.9906)
			(end -0.3048 -0.1016)
			(stroke
				(width 0.1)
				(type default)
			)
			(layer "B.Fab")
		)
		(pad "1" smd rect
			(at 0 0 270)
			(size 0.508 0.508)
			(layers "B.Cu" "B.Mask" "B.Paste")
			(net "A_TSENSE_PVCCIN_CPU0")
		)
		(pad "2" smd rect
			(at 0 0.889 270)
			(size 0.508 0.508)
			(layers "B.Cu" "B.Mask" "B.Paste")
			(net "GND")
		)
		(zone
			(layer "B.Cu")
			(hatch none 0.5)
			(connect_pads
				(clearance 0)
			)
			(min_thickness 0.25)
			(keepout
				(tracks allowed)
				(vias not_allowed)
				(pads allowed)
				(copperpour not_allowed)
				(footprints allowed)
			)
			(placement
				(enabled no)
				(sheetname "")
			)
			(fill
				(thermal_gap 0.5)
				(thermal_bridge_width 0.5)
				(island_removal_mode 0)
			)
			(polygon
				(pts
					(xy 195.4784 -56.134) (xy 195.4784 -55.626) (xy 195.8594 -55.626) (xy 195.8594 -56.134)
				)
			)
		)
		(zone
			(layer "B.Cu")
			(hatch none 0.5)
			(connect_pads
				(clearance 0)
			)
			(min_thickness 0.25)
			(keepout
				(tracks not_allowed)
				(vias allowed)
				(pads allowed)
				(copperpour not_allowed)
				(footprints allowed)
			)
			(placement
				(enabled no)
				(sheetname "")
			)
			(fill
				(thermal_gap 0.5)
				(thermal_bridge_width 0.5)
				(island_removal_mode 0)
			)
			(polygon
				(pts
					(xy 195.8594 -56.134) (xy 195.8594 -55.626) (xy 195.4784 -55.626) (xy 195.4784 -56.134)
				)
			)
		)
	)
	(footprint ""
		(layer "B.Cu")
		(at 374.777 -140.589 180)
		(property "Reference" "C3L21"
			(at -3.10007 3.24612 270)
			(unlocked yes)
			(layer "B.SilkS")
			(effects
				(font
					(size 0.7874 0.5842)
					(thickness 0.1524)
				)
				(justify mirror)
			)
		)
		(property "Value" ""
			(at 0 0 0)
			(layer "B.Fab")
			(effects
				(font
					(size 1.27 1.27)
				)
				(justify mirror)
			)
		)
		(duplicate_pad_numbers_are_jumpers no)
		(fp_line
			(start 2.563114 1.633728)
			(end 1.6002 1.633728)
			(stroke
				(width 0.1524)
				(type default)
			)
			(layer "B.SilkS")
		)
		(fp_line
			(start 2.563114 -1.616456)
			(end 2.563114 1.633728)
			(stroke
				(width 0.1524)
				(type default)
			)
			(layer "B.SilkS")
		)
		(fp_line
			(start 2.286 7.366)
			(end 2.286 1.632712)
			(stroke
				(width 0.1524)
				(type default)
			)
			(layer "B.SilkS")
		)
		(fp_line
			(start 2.286 7.366)
			(end 1.60147 7.366)
			(stroke
				(width 0.1524)
				(type default)
			)
			(layer "B.SilkS")
		)
		(fp_line
			(start 1.6002 -1.616456)
			(end 2.563114 -1.616456)
			(stroke
				(width 0.1524)
				(type default)
			)
			(layer "B.SilkS")
		)
		(fp_line
			(start -1.6002 -1.616456)
			(end -2.504948 -1.616456)
			(stroke
				(width 0.1524)
				(type default)
			)
			(layer "B.SilkS")
		)
		(fp_line
			(start -2.286 7.366)
			(end -1.600708 7.366)
			(stroke
				(width 0.1524)
				(type default)
			)
			(layer "B.SilkS")
		)
		(fp_line
			(start -2.286 7.366)
			(end -2.286 1.63195)
			(stroke
				(width 0.1524)
				(type default)
			)
			(layer "B.SilkS")
		)
		(fp_line
			(start -2.504948 1.633728)
			(end -1.6002 1.633728)
			(stroke
				(width 0.1524)
				(type default)
			)
			(layer "B.SilkS")
		)
		(fp_line
			(start -2.504948 -1.616456)
			(end -2.504948 1.633728)
			(stroke
				(width 0.1524)
				(type default)
			)
			(layer "B.SilkS")
		)
		(fp_rect
			(start 2.286 7.366)
			(end -2.286 -0.254)
			(stroke
				(width 0)
				(type default)
			)
			(fill no)
			(layer "B.CrtYd")
		)
		(fp_line
			(start 2.286 7.366)
			(end 2.286 -0.254)
			(stroke
				(width 0.1)
				(type default)
			)
			(layer "B.Fab")
		)
		(fp_line
			(start 2.286 -0.254)
			(end -2.286 -0.254)
			(stroke
				(width 0.1)
				(type default)
			)
			(layer "B.Fab")
		)
		(fp_line
			(start -2.286 7.366)
			(end 2.286 7.366)
			(stroke
				(width 0.1)
				(type default)
			)
			(layer "B.Fab")
		)
		(fp_line
			(start -2.286 -0.254)
			(end -2.286 7.366)
			(stroke
				(width 0.1)
				(type default)
			)
			(layer "B.Fab")
		)
		(pad "1" smd rect
			(at 0 0)
			(size 2.54 3.048)
			(layers "B.Cu" "B.Mask" "B.Paste")
			(net "PVNN_PCH_STBY")
		)
		(pad "2" smd rect
			(at 0 7.112)
			(size 2.54 3.048)
			(layers "B.Cu" "B.Mask" "B.Paste")
			(net "GND")
		)
	)
	(footprint ""
		(layer "B.Cu")
		(at 26.769568 -144.4752 180)
		(property "Reference" "C9L8"
			(at 0 0 0)
			(layer "B.SilkS")
			(hide yes)
			(effects
				(font
					(size 1.27 1.27)
				)
				(justify mirror)
			)
		)
		(property "Value" ""
			(at 0 0 0)
			(layer "B.Fab")
			(effects
				(font
					(size 1.27 1.27)
				)
				(justify mirror)
			)
		)
		(duplicate_pad_numbers_are_jumpers no)
		(fp_poly
			(pts
				(xy -0.3048 -0.1016) (xy -0.3048 0.9906) (xy 0.3048 0.9906) (xy 0.3048 -0.1016)
			)
			(stroke
				(width 0)
				(type default)
			)
			(fill no)
			(layer "B.CrtYd")
		)
		(fp_line
			(start 0.3048 0.9906)
			(end -0.3048 0.9906)
			(stroke
				(width 0.1)
				(type default)
			)
			(layer "B.Fab")
		)
		(fp_line
			(start 0.3048 -0.1016)
			(end 0.3048 0.9906)
			(stroke
				(width 0.1)
				(type default)
			)
			(layer "B.Fab")
		)
		(fp_line
			(start -0.3048 0.9906)
			(end -0.3048 -0.1016)
			(stroke
				(width 0.1)
				(type default)
			)
			(layer "B.Fab")
		)
		(fp_line
			(start -0.3048 -0.1016)
			(end 0.3048 -0.1016)
			(stroke
				(width 0.1)
				(type default)
			)
			(layer "B.Fab")
		)
		(pad "1" smd rect
			(at 0 0)
			(size 0.508 0.508)
			(layers "B.Cu" "B.Mask" "B.Paste")
			(net "M_L_CPU_VREF")
		)
		(pad "2" smd rect
			(at 0 0.889)
			(size 0.508 0.508)
			(layers "B.Cu" "B.Mask" "B.Paste")
			(net "GND")
		)
		(zone
			(layer "B.Cu")
			(hatch none 0.5)
			(connect_pads
				(clearance 0)
			)
			(min_thickness 0.25)
			(keepout
				(tracks not_allowed)
				(vias allowed)
				(pads allowed)
				(copperpour not_allowed)
				(footprints allowed)
			)
			(placement
				(enabled no)
				(sheetname "")
			)
			(fill
				(thermal_gap 0.5)
				(thermal_bridge_width 0.5)
				(island_removal_mode 0)
			)
			(polygon
				(pts
					(xy 26.515568 -145.1102) (xy 27.023568 -145.1102) (xy 27.023568 -144.7292) (xy 26.515568 -144.7292)
				)
			)
		)
		(zone
			(layer "B.Cu")
			(hatch none 0.5)
			(connect_pads
				(clearance 0)
			)
			(min_thickness 0.25)
			(keepout
				(tracks allowed)
				(vias not_allowed)
				(pads allowed)
				(copperpour not_allowed)
				(footprints allowed)
			)
			(placement
				(enabled no)
				(sheetname "")
			)
			(fill
				(thermal_gap 0.5)
				(thermal_bridge_width 0.5)
				(island_removal_mode 0)
			)
			(polygon
				(pts
					(xy 26.515568 -144.7292) (xy 27.023568 -144.7292) (xy 27.023568 -145.1102) (xy 26.515568 -145.1102)
				)
			)
		)
	)
	(footprint ""
		(layer "B.Cu")
		(at 405.358854 -35.09391 90)
		(property "Reference" "R25W122"
			(at 0.8382 -0.67818 90)
			(unlocked yes)
			(layer "B.SilkS")
			(effects
				(font
					(size 0.4064 0.254)
					(thickness 0.1524)
				)
				(justify left mirror)
			)
		)
		(property "Value" ""
			(at 0 0 90)
			(layer "B.Fab")
			(effects
				(font
					(size 1.27 1.27)
				)
				(justify mirror)
			)
		)
		(duplicate_pad_numbers_are_jumpers no)
		(fp_poly
			(pts
				(xy 0.2794 -0.1016) (xy -0.2794 -0.1016) (xy -0.2794 0.9906) (xy 0.2794 0.9906)
			)
			(stroke
				(width 0)
				(type default)
			)
			(fill no)
			(layer "B.CrtYd")
		)
		(fp_line
			(start 0.2794 -0.1016)
			(end 0.2794 0.9906)
			(stroke
				(width 0.1)
				(type default)
			)
			(layer "B.Fab")
		)
		(fp_line
			(start -0.2794 -0.1016)
			(end 0.2794 -0.1016)
			(stroke
				(width 0.1)
				(type default)
			)
			(layer "B.Fab")
		)
		(fp_line
			(start 0.2794 0.9906)
			(end -0.2794 0.9906)
			(stroke
				(width 0.1)
				(type default)
			)
			(layer "B.Fab")
		)
		(fp_line
			(start -0.2794 0.9906)
			(end -0.2794 -0.1016)
			(stroke
				(width 0.1)
				(type default)
			)
			(layer "B.Fab")
		)
		(pad "1" smd rect
			(at 0 0 270)
			(size 0.508 0.508)
			(layers "B.Cu" "B.Mask" "B.Paste")
			(net "SMB_PEHPCPU0_STBY_LVC3_R_SCL")
		)
		(pad "2" smd rect
			(at 0 0.889 270)
			(size 0.508 0.508)
			(layers "B.Cu" "B.Mask" "B.Paste")
			(net "SMB_PEHPCPU0_STBY_LVC3_R2_SCL")
		)
		(zone
			(layer "B.Cu")
			(hatch none 0.5)
			(connect_pads
				(clearance 0)
			)
			(min_thickness 0.25)
			(keepout
				(tracks allowed)
				(vias not_allowed)
				(pads allowed)
				(copperpour not_allowed)
				(footprints allowed)
			)
			(placement
				(enabled no)
				(sheetname "")
			)
			(fill
				(thermal_gap 0.5)
				(thermal_bridge_width 0.5)
				(island_removal_mode 0)
			)
			(polygon
				(pts
					(xy 405.612854 -35.34791) (xy 405.612854 -34.83991) (xy 405.993854 -34.83991) (xy 405.993854 -35.34791)
				)
			)
		)
		(zone
			(layer "B.Cu")
			(hatch none 0.5)
			(connect_pads
				(clearance 0)
			)
			(min_thickness 0.25)
			(keepout
				(tracks not_allowed)
				(vias allowed)
				(pads allowed)
				(copperpour not_allowed)
				(footprints allowed)
			)
			(placement
				(enabled no)
				(sheetname "")
			)
			(fill
				(thermal_gap 0.5)
				(thermal_bridge_width 0.5)
				(island_removal_mode 0)
			)
			(polygon
				(pts
					(xy 405.993854 -35.34791) (xy 405.993854 -34.83991) (xy 405.612854 -34.83991) (xy 405.612854 -35.34791)
				)
			)
		)
	)
	(footprint ""
		(layer "B.Cu")
		(at 355.736398 -77.915516)
		(property "Reference" "C3P34"
			(at 0 0 0)
			(layer "B.SilkS")
			(hide yes)
			(effects
				(font
					(size 1.27 1.27)
				)
				(justify mirror)
			)
		)
		(property "Value" ""
			(at 0 0 0)
			(layer "B.Fab")
			(effects
				(font
					(size 1.27 1.27)
				)
				(justify mirror)
			)
		)
		(duplicate_pad_numbers_are_jumpers no)
		(fp_poly
			(pts
				(xy -0.3048 -0.1016) (xy -0.3048 0.9906) (xy 0.3048 0.9906) (xy 0.3048 -0.1016)
			)
			(stroke
				(width 0)
				(type default)
			)
			(fill no)
			(layer "B.CrtYd")
		)
		(fp_line
			(start -0.3048 -0.1016)
			(end 0.3048 -0.1016)
			(stroke
				(width 0.1)
				(type default)
			)
			(layer "B.Fab")
		)
		(fp_line
			(start -0.3048 0.9906)
			(end -0.3048 -0.1016)
			(stroke
				(width 0.1)
				(type default)
			)
			(layer "B.Fab")
		)
		(fp_line
			(start 0.3048 -0.1016)
			(end 0.3048 0.9906)
			(stroke
				(width 0.1)
				(type default)
			)
			(layer "B.Fab")
		)
		(fp_line
			(start 0.3048 0.9906)
			(end -0.3048 0.9906)
			(stroke
				(width 0.1)
				(type default)
			)
			(layer "B.Fab")
		)
		(pad "1" smd rect
			(at 0 0 180)
			(size 0.508 0.508)
			(layers "B.Cu" "B.Mask" "B.Paste")
			(net "P3E_CPU0_PE1_SS_TXP<6>")
		)
		(pad "2" smd rect
			(at 0 0.889 180)
			(size 0.508 0.508)
			(layers "B.Cu" "B.Mask" "B.Paste")
			(net "P3E_CPU0_PE1_SS_C_TXP<6>")
		)
		(zone
			(layer "B.Cu")
			(hatch none 0.5)
			(connect_pads
				(clearance 0)
			)
			(min_thickness 0.25)
			(keepout
				(tracks allowed)
				(vias not_allowed)
				(pads allowed)
				(copperpour not_allowed)
				(footprints allowed)
			)
			(placement
				(enabled no)
				(sheetname "")
			)
			(fill
				(thermal_gap 0.5)
				(thermal_bridge_width 0.5)
				(island_removal_mode 0)
			)
			(polygon
				(pts
					(xy 355.990398 -77.661516) (xy 355.482398 -77.661516) (xy 355.482398 -77.280516) (xy 355.990398 -77.280516)
				)
			)
		)
		(zone
			(layer "B.Cu")
			(hatch none 0.5)
			(connect_pads
				(clearance 0)
			)
			(min_thickness 0.25)
			(keepout
				(tracks not_allowed)
				(vias allowed)
				(pads allowed)
				(copperpour not_allowed)
				(footprints allowed)
			)
			(placement
				(enabled no)
				(sheetname "")
			)
			(fill
				(thermal_gap 0.5)
				(thermal_bridge_width 0.5)
				(island_removal_mode 0)
			)
			(polygon
				(pts
					(xy 355.990398 -77.280516) (xy 355.482398 -77.280516) (xy 355.482398 -77.661516) (xy 355.990398 -77.661516)
				)
			)
		)
	)
)
